# SCM (Grand Teton) — schematic netlist excerpt (pin names and nets, part order shuffled) for the footprints in the layout excerpt that follows; sources: Cadence DE-HDL packaged netlist, KiCad conversion of 12092022_DA0F0TMDCD0_F0T_Management_Board_D_brd_V3_OCP.brd

R329  Q_RES  120 1% CHIP  pkg 0402LF  page 20 : A = GND ; B = M_BMC_DDR4_MA<3>
C167  Q_CAP  0.1UF 25V 10% X7R  pkg 0402  page 41 : A = VCCIO1 ; B = GND

(kicad_pcb
	(version 20260206)
	(generator "pcbnew")
	(generator_version "10.0")
	(general
		(thickness 1.6)
		(legacy_teardrops no)
	)
	(paper "A4")
	(title_block
		(title "12092022_DA0F0TMDCD0_F0T_Management_Board_D_brd_V3_OCP.brd")
		(comment 1 "Grand Teton / footprints 966-967 of 1440")
	)
	(layers
		(0 "F.Cu" signal "TOP")
		(4 "In1.Cu" signal "GND")
		(6 "In2.Cu" signal "IN1")
		(8 "In3.Cu" signal "GND1")
		(10 "In4.Cu" signal "IN2")
		(12 "In5.Cu" signal "VCC")
		(14 "In6.Cu" signal "VCC1")
		(16 "In7.Cu" signal "IN3")
		(18 "In8.Cu" signal "GND2")
		(20 "In9.Cu" signal "IN4")
		(22 "In10.Cu" signal "GND3")
		(2 "B.Cu" signal "BOTTOM")
		(9 "F.Adhes" user "F.Adhesive")
		(11 "B.Adhes" user "B.Adhesive")
		(13 "F.Paste" user "Package Geometry/Pastemask Top")
		(15 "B.Paste" user "Package Geometry/Pastemask Bottom")
		(5 "F.SilkS" user "Ref Des/Silkscreen Top")
		(7 "B.SilkS" user "Ref Des/Silkscreen Bottom")
		(1 "F.Mask" user "Board Geometry/Soldermask Top")
		(3 "B.Mask" user "Board Geometry/Soldermask Bottom")
		(17 "Dwgs.User" user "User.Drawings")
		(19 "Cmts.User" user "User.Comments")
		(21 "Eco1.User" user "User.Eco1")
		(23 "Eco2.User" user "User.Eco2")
		(25 "Edge.Cuts" user "Board Geometry/Outline")
		(27 "Margin" user)
		(31 "F.CrtYd" user "Package Geometry/Place Bound Top")
		(29 "B.CrtYd" user "Package Geometry/Place Bound Bottom")
		(35 "F.Fab" user "Ref Des/Assembly Top")
		(33 "B.Fab" user "Ref Des/Assembly Bottom")
	)
	(footprint ""
		(layer "B.Cu")
		(at 18.259552 -90.786966 180)
		(property "Reference" "C167"
			(at 0 0 0)
			(layer "B.SilkS")
			(hide yes)
			(effects
				(font
					(size 1.27 1.27)
				)
				(justify mirror)
			)
		)
		(property "Value" ""
			(at 0 0 0)
			(layer "B.Fab")
			(effects
				(font
					(size 1.27 1.27)
				)
				(justify mirror)
			)
		)
		(duplicate_pad_numbers_are_jumpers no)
		(fp_line
			(start 0.69215 0.2921)
			(end 0.69215 -0.2921)
			(stroke
				(width 0.1524)
				(type default)
			)
			(layer "B.SilkS")
		)
		(fp_line
			(start 0.69215 -0.2921)
			(end -0.69215 -0.2921)
			(stroke
				(width 0.1524)
				(type default)
			)
			(layer "B.SilkS")
		)
		(fp_line
			(start -0.69215 0.2921)
			(end 0.69215 0.2921)
			(stroke
				(width 0.1524)
				(type default)
			)
			(layer "B.SilkS")
		)
		(fp_line
			(start -0.69215 -0.2921)
			(end -0.69215 0.2921)
			(stroke
				(width 0.1524)
				(type default)
			)
			(layer "B.SilkS")
		)
		(fp_line
			(start 0.51435 0.2794)
			(end 0.51435 -0.2794)
			(stroke
				(width 0.1)
				(type default)
			)
			(layer "B.Fab")
		)
		(fp_line
			(start 0.51435 -0.2794)
			(end -0.51435 -0.2794)
			(stroke
				(width 0.1)
				(type default)
			)
			(layer "B.Fab")
		)
		(fp_line
			(start -0.51435 0.2794)
			(end 0.51435 0.2794)
			(stroke
				(width 0.1)
				(type default)
			)
			(layer "B.Fab")
		)
		(fp_line
			(start -0.51435 -0.2794)
			(end -0.51435 0.2794)
			(stroke
				(width 0.1)
				(type default)
			)
			(layer "B.Fab")
		)
		(pad "1" smd circle
			(at 0.40005 0)
			(size 0 0)
			(layers "B.Cu" "B.Mask" "B.Paste")
			(net "VCCIO1")
		)
		(pad "2" smd circle
			(at -0.40005 0)
			(size 0 0)
			(layers "B.Cu" "B.Mask" "B.Paste")
			(net "GND")
		)
		(zone
			(layer "B.Cu")
			(hatch none 0.5)
			(connect_pads
				(clearance 0)
			)
			(min_thickness 0.25)
			(keepout
				(tracks not_allowed)
				(vias allowed)
				(pads allowed)
				(copperpour not_allowed)
				(footprints allowed)
			)
			(placement
				(enabled no)
				(sheetname "")
			)
			(fill
				(thermal_gap 0.5)
				(thermal_bridge_width 0.5)
				(island_removal_mode 0)
			)
			(polygon
				(pts
					(xy 18.069052 -90.874596) (xy 18.160492 -90.932762) (xy 18.359882 -90.932762) (xy 18.450052 -90.874596)
					(xy 18.450052 -90.699336) (xy 18.359882 -90.640916) (xy 18.160492 -90.640916) (xy 18.069052 -90.699082)
				)
			)
		)
	)
	(footprint ""
		(layer "B.Cu")
		(at 81.129886 -42.006012)
		(property "Reference" "R329"
			(at 0 0 0)
			(layer "B.SilkS")
			(hide yes)
			(effects
				(font
					(size 1.27 1.27)
				)
				(justify mirror)
			)
		)
		(property "Value" ""
			(at 0 0 0)
			(layer "B.Fab")
			(effects
				(font
					(size 1.27 1.27)
				)
				(justify mirror)
			)
		)
		(duplicate_pad_numbers_are_jumpers no)
		(fp_line
			(start -0.7874 -0.4064)
			(end -0.7874 0.4064)
			(stroke
				(width 0.1524)
				(type default)
			)
			(layer "B.SilkS")
		)
		(fp_line
			(start -0.7874 0.4064)
			(end 0.7874 0.4064)
			(stroke
				(width 0.1524)
				(type default)
			)
			(layer "B.SilkS")
		)
		(fp_line
			(start 0.7874 -0.4064)
			(end -0.7874 -0.4064)
			(stroke
				(width 0.1524)
				(type default)
			)
			(layer "B.SilkS")
		)
		(fp_line
			(start 0.7874 0.4064)
			(end 0.7874 -0.4064)
			(stroke
				(width 0.1524)
				(type default)
			)
			(layer "B.SilkS")
		)
		(fp_line
			(start -0.67945 -0.3048)
			(end -0.67945 0.3048)
			(stroke
				(width 0.1)
				(type default)
			)
			(layer "B.Fab")
		)
		(fp_line
			(start -0.67945 0.3048)
			(end -0.120396 0.3048)
			(stroke
				(width 0.1)
				(type default)
			)
			(layer "B.Fab")
		)
		(fp_line
			(start -0.12065 -0.3048)
			(end -0.67945 -0.3048)
			(stroke
				(width 0.1)
				(type default)
			)
			(layer "B.Fab")
		)
		(fp_line
			(start -0.12065 -0.2794)
			(end -0.12065 -0.3048)
			(stroke
				(width 0.1)
				(type default)
			)
			(layer "B.Fab")
		)
		(fp_line
			(start -0.120396 0.2794)
			(end 0.12065 0.2794)
			(stroke
				(width 0.1)
				(type default)
			)
			(layer "B.Fab")
		)
		(fp_line
			(start -0.120396 0.3048)
			(end -0.120396 0.2794)
			(stroke
				(width 0.1)
				(type default)
			)
			(layer "B.Fab")
		)
		(fp_line
			(start 0.12065 -0.305054)
			(end 0.12065 -0.2794)
			(stroke
				(width 0.1)
				(type default)
			)
			(layer "B.Fab")
		)
		(fp_line
			(start 0.12065 -0.2794)
			(end -0.12065 -0.2794)
			(stroke
				(width 0.1)
				(type default)
			)
			(layer "B.Fab")
		)
		(fp_line
			(start 0.12065 0.2794)
			(end 0.12065 0.3048)
			(stroke
				(width 0.1)
				(type default)
			)
			(layer "B.Fab")
		)
		(fp_line
			(start 0.12065 0.3048)
			(end 0.67945 0.3048)
			(stroke
				(width 0.1)
				(type default)
			)
			(layer "B.Fab")
		)
		(fp_line
			(start 0.67945 -0.305054)
			(end 0.12065 -0.305054)
			(stroke
				(width 0.1)
				(type default)
			)
			(layer "B.Fab")
		)
		(fp_line
			(start 0.67945 0.3048)
			(end 0.67945 -0.305054)
			(stroke
				(width 0.1)
				(type default)
			)
			(layer "B.Fab")
		)
		(pad "1" smd circle
			(at 0.40005 0 180)
			(size 0 0)
			(layers "B.Cu" "B.Mask" "B.Paste")
			(net "GND")
		)
		(pad "2" smd circle
			(at -0.40005 0 180)
			(size 0 0)
			(layers "B.Cu" "B.Mask" "B.Paste")
			(net "M_BMC_DDR4_MA<3>")
		)
	)
)
